# T6G (Grand Teton) — schematic netlist excerpt (pin names and nets, part order shuffled) for the footprints in the layout excerpt that follows; sources: Cadence DE-HDL packaged netlist, KiCad conversion of 04192023_DAF0TMB3IC0_F0TG_MB_C_brd_V02_OCP.brd

PC8006  Q_CAP  22UF 16V 20% X6S  pkg C0805  page 225 : A = SW_P12V_AUX_PVDD11_S3_P1_FLT ; B = GND
R1590  Q_RES  49.9 1% CHIP  pkg 0402LF  page 108 : A = I3C_SPD_DDRGL_CPU1_SCL ; B = I3C_SPD_DDRK_CPU1_SCL
R1105  Q_RES  4.7K 5% EMPTY  pkg 0201LF  page 309 : A = P1V8_CPU0_RT_1D ; B = RT_CPU0_P3_SCAN_MODE

(kicad_pcb
	(version 20260206)
	(generator "pcbnew")
	(generator_version "10.0")
	(general
		(thickness 1.6)
		(legacy_teardrops no)
	)
	(paper "A4")
	(title_block
		(title "04192023_DAF0TMB3IC0_F0TG_MB_C_brd_V02_OCP.brd")
		(comment 1 "Grand Teton / footprints 7705-7707 of 8354")
	)
	(layers
		(0 "F.Cu" signal "TOP")
		(4 "In1.Cu" signal "GND")
		(6 "In2.Cu" signal "IN1")
		(8 "In3.Cu" signal "GND1")
		(10 "In4.Cu" signal "IN2")
		(12 "In5.Cu" signal "GND2")
		(14 "In6.Cu" signal "IN3")
		(16 "In7.Cu" signal "GND3")
		(18 "In8.Cu" signal "VCC")
		(20 "In9.Cu" signal "VCC1")
		(22 "In10.Cu" signal "GND4")
		(24 "In11.Cu" signal "IN4")
		(26 "In12.Cu" signal "GND5")
		(28 "In13.Cu" signal "IN5")
		(30 "In14.Cu" signal "GND6")
		(32 "In15.Cu" signal "IN6")
		(34 "In16.Cu" signal "GND7")
		(2 "B.Cu" signal "BOTTOM")
		(9 "F.Adhes" user "F.Adhesive")
		(11 "B.Adhes" user "B.Adhesive")
		(13 "F.Paste" user "Package Geometry/Pastemask Top")
		(15 "B.Paste" user "Package Geometry/Pastemask Bottom")
		(5 "F.SilkS" user "Ref Des/Silkscreen Top")
		(7 "B.SilkS" user "Ref Des/Silkscreen Bottom")
		(1 "F.Mask" user "Board Geometry/Soldermask Top")
		(3 "B.Mask" user "Board Geometry/Soldermask Bottom")
		(17 "Dwgs.User" user "User.Drawings")
		(19 "Cmts.User" user "User.Comments")
		(21 "Eco1.User" user "User.Eco1")
		(23 "Eco2.User" user "User.Eco2")
		(25 "Edge.Cuts" user "Board Geometry/Outline")
		(27 "Margin" user)
		(31 "F.CrtYd" user "Package Geometry/Place Bound Top")
		(29 "B.CrtYd" user "Package Geometry/Place Bound Bottom")
		(35 "F.Fab" user "Ref Des/Assembly Top")
		(33 "B.Fab" user "Ref Des/Assembly Bottom")
	)
	(footprint ""
		(layer "B.Cu")
		(at 197.94855 -194.8942 180)
		(property "Reference" "R1590"
			(at 0 0 0)
			(layer "B.SilkS")
			(hide yes)
			(effects
				(font
					(size 1.27 1.27)
				)
				(justify mirror)
			)
		)
		(property "Value" ""
			(at 0 0 0)
			(layer "B.Fab")
			(effects
				(font
					(size 1.27 1.27)
				)
				(justify mirror)
			)
		)
		(duplicate_pad_numbers_are_jumpers no)
		(fp_line
			(start 0.7874 0.4064)
			(end 0.7874 -0.4064)
			(stroke
				(width 0.1524)
				(type default)
			)
			(layer "B.SilkS")
		)
		(fp_line
			(start 0.7874 -0.4064)
			(end -0.7874 -0.4064)
			(stroke
				(width 0.1524)
				(type default)
			)
			(layer "B.SilkS")
		)
		(fp_line
			(start -0.7874 0.4064)
			(end 0.7874 0.4064)
			(stroke
				(width 0.1524)
				(type default)
			)
			(layer "B.SilkS")
		)
		(fp_line
			(start -0.7874 -0.4064)
			(end -0.7874 0.4064)
			(stroke
				(width 0.1524)
				(type default)
			)
			(layer "B.SilkS")
		)
		(fp_line
			(start 0.67945 0.3048)
			(end 0.67945 -0.305054)
			(stroke
				(width 0.1)
				(type default)
			)
			(layer "B.Fab")
		)
		(fp_line
			(start 0.67945 -0.305054)
			(end 0.12065 -0.305054)
			(stroke
				(width 0.1)
				(type default)
			)
			(layer "B.Fab")
		)
		(fp_line
			(start 0.12065 0.3048)
			(end 0.67945 0.3048)
			(stroke
				(width 0.1)
				(type default)
			)
			(layer "B.Fab")
		)
		(fp_line
			(start 0.12065 0.2794)
			(end 0.12065 0.3048)
			(stroke
				(width 0.1)
				(type default)
			)
			(layer "B.Fab")
		)
		(fp_line
			(start 0.12065 -0.2794)
			(end -0.12065 -0.2794)
			(stroke
				(width 0.1)
				(type default)
			)
			(layer "B.Fab")
		)
		(fp_line
			(start 0.12065 -0.305054)
			(end 0.12065 -0.2794)
			(stroke
				(width 0.1)
				(type default)
			)
			(layer "B.Fab")
		)
		(fp_line
			(start -0.120396 0.3048)
			(end -0.120396 0.2794)
			(stroke
				(width 0.1)
				(type default)
			)
			(layer "B.Fab")
		)
		(fp_line
			(start -0.120396 0.2794)
			(end 0.12065 0.2794)
			(stroke
				(width 0.1)
				(type default)
			)
			(layer "B.Fab")
		)
		(fp_line
			(start -0.12065 -0.2794)
			(end -0.12065 -0.3048)
			(stroke
				(width 0.1)
				(type default)
			)
			(layer "B.Fab")
		)
		(fp_line
			(start -0.12065 -0.3048)
			(end -0.67945 -0.3048)
			(stroke
				(width 0.1)
				(type default)
			)
			(layer "B.Fab")
		)
		(fp_line
			(start -0.67945 0.3048)
			(end -0.120396 0.3048)
			(stroke
				(width 0.1)
				(type default)
			)
			(layer "B.Fab")
		)
		(fp_line
			(start -0.67945 -0.3048)
			(end -0.67945 0.3048)
			(stroke
				(width 0.1)
				(type default)
			)
			(layer "B.Fab")
		)
		(pad "1" smd circle
			(at 0.40005 0)
			(size 0 0)
			(layers "B.Cu" "B.Mask" "B.Paste")
			(net "I3C_SPD_DDRGL_CPU1_SCL")
		)
		(pad "2" smd circle
			(at -0.40005 0)
			(size 0 0)
			(layers "B.Cu" "B.Mask" "B.Paste")
			(net "I3C_SPD_DDRK_CPU1_SCL")
		)
	)
	(footprint ""
		(layer "B.Cu")
		(at 185.166 -359.537)
		(property "Reference" "PC8006"
			(at 0 0 0)
			(layer "B.SilkS")
			(hide yes)
			(effects
				(font
					(size 1.27 1.27)
				)
				(justify mirror)
			)
		)
		(property "Value" ""
			(at 0 0 0)
			(layer "B.Fab")
			(effects
				(font
					(size 1.27 1.27)
				)
				(justify mirror)
			)
		)
		(duplicate_pad_numbers_are_jumpers no)
		(fp_line
			(start -1.524 -0.762)
			(end -1.524 0.762)
			(stroke
				(width 0.1524)
				(type default)
			)
			(layer "B.SilkS")
		)
		(fp_line
			(start -1.524 0.762)
			(end 1.524 0.762)
			(stroke
				(width 0.1524)
				(type default)
			)
			(layer "B.SilkS")
		)
		(fp_line
			(start 1.524 -0.762)
			(end -1.524 -0.762)
			(stroke
				(width 0.1524)
				(type default)
			)
			(layer "B.SilkS")
		)
		(fp_line
			(start 1.524 0.762)
			(end 1.524 -0.762)
			(stroke
				(width 0.1524)
				(type default)
			)
			(layer "B.SilkS")
		)
		(fp_line
			(start -1.1049 -0.724916)
			(end 1.1049 -0.724916)
			(stroke
				(width 0.1)
				(type default)
			)
			(layer "B.Fab")
		)
		(fp_line
			(start -1.1049 0.724916)
			(end -1.1049 -0.724916)
			(stroke
				(width 0.1)
				(type default)
			)
			(layer "B.Fab")
		)
		(fp_line
			(start 1.1049 -0.724916)
			(end 1.1049 0.724916)
			(stroke
				(width 0.1)
				(type default)
			)
			(layer "B.Fab")
		)
		(fp_line
			(start 1.1049 0.724916)
			(end -1.1049 0.724916)
			(stroke
				(width 0.1)
				(type default)
			)
			(layer "B.Fab")
		)
		(pad "1" smd rect
			(at 0.889 0)
			(size 1.016 1.27)
			(layers "B.Cu" "B.Mask" "B.Paste")
			(net "SW_P12V_AUX_PVDD11_S3_P1_FLT")
		)
		(pad "2" smd rect
			(at -0.889 0)
			(size 1.016 1.27)
			(layers "B.Cu" "B.Mask" "B.Paste")
			(net "GND")
		)
	)
	(footprint ""
		(layer "B.Cu")
		(at 365.09579 -392.1252 180)
		(property "Reference" "R1105"
			(at 0 0 0)
			(layer "B.SilkS")
			(hide yes)
			(effects
				(font
					(size 1.27 1.27)
				)
				(justify mirror)
			)
		)
		(property "Value" ""
			(at 0 0 0)
			(layer "B.Fab")
			(effects
				(font
					(size 1.27 1.27)
				)
				(justify mirror)
			)
		)
		(duplicate_pad_numbers_are_jumpers no)
		(fp_line
			(start 0.32512 0.175006)
			(end 0.32512 -0.175006)
			(stroke
				(width 0.1)
				(type default)
			)
			(layer "B.Fab")
		)
		(fp_line
			(start 0.32512 -0.175006)
			(end -0.32512 -0.175006)
			(stroke
				(width 0.1)
				(type default)
			)
			(layer "B.Fab")
		)
		(fp_line
			(start -0.32512 0.175006)
			(end 0.32512 0.175006)
			(stroke
				(width 0.1)
				(type default)
			)
			(layer "B.Fab")
		)
		(fp_line
			(start -0.32512 -0.175006)
			(end -0.32512 0.175006)
			(stroke
				(width 0.1)
				(type default)
			)
			(layer "B.Fab")
		)
		(pad "1" smd rect
			(at 0.2667 0)
			(size 0.3048 0.381)
			(layers "B.Cu" "B.Mask" "B.Paste")
			(net "P1V8_CPU0_RT_1D")
		)
		(pad "2" smd rect
			(at -0.2667 0 180)
			(size 0.3048 0.381)
			(layers "B.Cu" "B.Mask" "B.Paste")
			(net "RT_CPU0_P3_SCAN_MODE")
		)
	)
)
